FILE_TYPE = CONNECTIVITY;
{Allegro Design Entry HDL 17.4-2019 S026 (4007227) 1/17/2022}
"PAGE_NUMBER" = 144;
0"NC";
1"GND\g";
2"P1V8_AUX\g";
3"P1V8_AUX\g";
4"GND\g";
5"GND\g";
6"GND\g";
7"GND\g";
8"P3V3_AUX\g";
9"P1V8_AUX\g";
10"GND\g";
11"P1V8_AUX\g";
12"GND\g";
13"P1V8_AUX\g";
14"GND\g";
15"P1V8_AUX\g";
16"GND\g";
17"P3V3_AUX\g";
18"GND\g";
19"P1V8_AUX\g";
20"P1V8_AUX\g";
21"P3V3_AUX\g";
22"P3V3_AUX\g";
23"GND\g";
24"PVDD18_S5_P0\g";
25"PVDD18_S5_P0\g";
26"P1V8_AUX\g";
27"P3V3_AUX\g";
28"FM_PASSWORD_CLEAR_N";
29"BIOS_DEBUG_MODE";
30"FM_FORCE_ALL_PWRON";
31"FM_BIOS_USB_RECOVERY";
32"PU_FPGA_DEBUG_SW_SPARE";
33"PD_BIOS_DEBUG_MODE";
34"BIOS_DEBUG_MODE";
35"FM_PASSWORD_CLEAR_N";
36"FPGA_DEBUG_LED_CTRL";
37"PU_FPGA_DEBUG_LED_CTRL";
38"FM_PRSNT_CPU0_N";
39"FM_PRSNT_CPU1_N";
40"PU_BIOS_USB_RECOVERY";
41"FPGA_DEBUG_LED_CTRL";
42"FM_SPD_CPU0_SWITCH_CTRL_N";
43"BMC_JTAG_SEL";
44"FM_BIOS_USB_RECOVERY";
45"PU_FPGA_DEBUG_LED_CTRL";
46"FPGA_DEBUG_SW_SPARE";
47"PU_FPGA_DEBUG_SW_SPARE";
48"JTAG_BMC_OE";
49"JTAG_BMC_OE";
50"FM_JTAG_BMC_R_OE";
51"FM_JTAG_BMC_R_OE";
52"PRSNT_CPU0_N";
53"PRSNT_CPU1_N";
54"FM_PRSNT_CPU0_N";
55"FM_FORCE_ALL_PWRON";
56"FM_SPD_CPU0_SWITCH_CTRL_N";
57"FM_FORCE_ALL_PWRON_ON";
58"PU_BIOS_USB_RECOVERY";
59"FM_PRSNT_CPU1_N";
60"FPGA_DEBUG_SW_SPARE";
61"BMC_JTAG_SEL";
62"U124_VCC";
63"FM_FORCE_ALL_PWRON_ON";
%"UNIVERSAL_GND"
"1","(-8200,1200)","5","pure_quanta_power","I10";
;
CDS_LIB"pure_quanta_power"
HDL_POWER"GND";
"A"1;
%"Q_RES"
"2","(-8200,5800)","2","pure_quanta","I15";
;
LOCATION"R1261"
$SEC"1"
CDS_SEC"1"
VALUE"10K"
PACK_TYPE"0402LF"
TOLERANCE"5%"
MATERIAL"CHIP"
WATTAGE"1/16W"
CDS_LIB"pure_quanta"
PART_NUMBER"CS31002JB08";
"A"
$PN"1"2;
"B"
$PN"2"42;
%"UNIVERSAL_POWER"
"1","(-8200,6000)","2","pure_quanta_power","I16";
;
HDL_POWER"P1V8_AUX"
CDS_LIB"pure_quanta_power";
"A"2;
%"Q_RES"
"1","(-7600,300)","0","pure_quanta","I17";
;
LOCATION"R744"
$SEC"1"
CDS_SEC"1"
VALUE"0"
CDS_LIB"pure_quanta"
BOM_COST"MEM"
WATTAGE"1/16W"
MATERIAL"CHIP"
TOLERANCE"5%"
PACK_TYPE"0402LF"
PART_NUMBER"CS00002JB13";
"B"
$PN"2"59;
"A"
$PN"1"53;
%"Q_RES"
"1","(-7600,525)","0","pure_quanta","I19";
;
LOCATION"R734"
$SEC"1"
CDS_SEC"1"
VALUE"0"
CDS_LIB"pure_quanta"
BOM_COST"MEM"
WATTAGE"1/16W"
MATERIAL"CHIP"
TOLERANCE"5%"
PACK_TYPE"0402LF"
PART_NUMBER"CS00002JB13";
"B"
$PN"2"54;
"A"
$PN"1"52;
%"Q_RES"
"2","(-8075,2550)","2","pure_quanta","I30";
;
LOCATION"R1262"
$SEC"1"
CDS_SEC"1"
VALUE"10K"
PACK_TYPE"0402LF"
TOLERANCE"5%"
MATERIAL"CHIP"
WATTAGE"1/16W"
CDS_LIB"pure_quanta"
PART_NUMBER"CS31002JB08";
"A"
$PN"1"3;
"B"
$PN"2"43;
%"UNIVERSAL_POWER"
"1","(-8075,2750)","2","pure_quanta_power","I31";
;
HDL_POWER"P1V8_AUX"
CDS_LIB"pure_quanta_power";
"A"3;
%"UNIVERSAL_GND"
"1","(-7950,3425)","2","pure_quanta_power","I32";
;
CDS_LIB"pure_quanta_power"
HDL_POWER"GND";
"A"4;
%"Q_RES"
"2","(-7950,3625)","2","pure_quanta","I33";
;
LOCATION"R6044"
$SEC"1"
CDS_SEC"1"
VALUE"10K"
PACK_TYPE"0402LF"
TOLERANCE"5%"
MATERIAL"CHIP"
WATTAGE"1/16W"
CDS_LIB"pure_quanta"
PART_NUMBER"CS31002JB08";
"A"
$PN"1"30;
"B"
$PN"2"4;
%"Q_RES"
"2","(-7950,4100)","2","pure_quanta","I34";
;
LOCATION"R5071"
$SEC"1"
CDS_SEC"1"
VALUE"100"
PACK_TYPE"0402LF"
MATERIAL"CHIP"
WATTAGE"1/16W"
CDS_LIB"pure_quanta"
TOLERANCE"1%"
PART_NUMBER"CS11002FB07";
"A"
$PN"1"11;
"B"
$PN"2"63;
%"UNIVERSAL_GND"
"1","(-4875,800)","0","pure_quanta_power","I36";
;
CDS_LIB"pure_quanta_power"
HDL_POWER"GND";
"A"5;
%"UNIVERSAL_GND"
"1","(-4750,500)","0","pure_quanta_power","I37";
;
CDS_LIB"pure_quanta_power"
HDL_POWER"GND";
"A"6;
%"SN74LVC1G07DBVR"
"1","(-4475,700)","0","pure_quanta","I38";
;
LOCATION"U124"
$SEC"1"
CDS_SEC"1"
MATERIAL"IC"
PACK_TYPE"SMLF"
VALUE"SN74LVC1G07DBVR"
NEEDS_NO_SIZE"TRUE"
CDS_LIB"pure_quanta"
PART_NUMBER"AL1G0007024";
"NC"
$PN"1"0;
"Y"
$PN"4"49;
"GND"
$PN"3"6;
"A"
$PN"2"50;
"VCC"
$PN"5"62;
%"Q_CAP"
"1","(-4875,1075)","0","pure_quanta","I39";
;
LOCATION"C693"
$SEC"1"
CDS_SEC"1"
PACK_TYPE"0402"
MATERIAL"X7R"
VOLTAGE"25V"
VALUE"0.1UF"
CDS_LIB"pure_quanta"
TOLERANCE"10%"
PART_NUMBER"CH4104K1B00";
"B"
$PN"2"5;
"A"
$PN"1"62;
%"UNIVERSAL_GND"
"1","(-8325,900)","5","pure_quanta_power","I4";
;
CDS_LIB"pure_quanta_power"
HDL_POWER"GND";
"A"7;
%"UNIVERSAL_POWER"
"1","(-4750,1825)","2","pure_quanta_power","I40";
;
HDL_POWER"P3V3_AUX"
CDS_LIB"pure_quanta_power";
"A"8;
%"Q_RES"
"2","(-5025,2450)","2","pure_quanta","I44";
;
LOCATION"R1264"
$SEC"1"
CDS_SEC"1"
VALUE"1K"
MATERIAL"EMPTY"
TOLERANCE"1%"
PACK_TYPE"0402LF"
WATTAGE"1/16W"
CDS_LIB"pure_quanta"
PART_NUMBER"CS21002FB06";
"A"
$PN"1"9;
"B"
$PN"2"29;
%"UNIVERSAL_POWER"
"1","(-5025,2650)","2","pure_quanta_power","I45";
;
HDL_POWER"P1V8_AUX"
CDS_LIB"pure_quanta_power";
"A"9;
%"UNIVERSAL_GND"
"1","(-4300,3550)","2","pure_quanta_power","I46";
;
CDS_LIB"pure_quanta_power"
HDL_POWER"GND";
"A"10;
%"Q_RES"
"1","(-4300,3900)","1","pure_quanta","I47";
;
LOCATION"R8"
$SEC"1"
CDS_SEC"1"
MATERIAL"CHIP"
VALUE"100K"
CDS_LIB"pure_quanta"
PACK_TYPE"0402LF"
WATTAGE"1/16W"
TOLERANCE"1%"
PART_NUMBER"CS41002FB09";
"B"
$PN"2"48;
"A"
$PN"1"10;
%"UNIVERSAL_POWER"
"1","(-7950,4300)","2","pure_quanta_power","I48";
;
HDL_POWER"P1V8_AUX"
CDS_LIB"pure_quanta_power";
"A"11;
%"UNIVERSAL_GND"
"1","(-9125,1050)","5","pure_quanta_power","I5";
;
CDS_LIB"pure_quanta_power"
HDL_POWER"GND";
"A"12;
%"Q_RES"
"2","(-4800,4250)","0","pure_quanta","I50";
;
LOCATION"R733"
$SEC"1"
CDS_SEC"1"
WATTAGE"1/16W"
MATERIAL"EMPTY"
PACK_TYPE"0402LF"
VALUE"100"
TOLERANCE"1%"
CDS_LIB"pure_quanta"
PART_NUMBER"CS11002FB07";
"A"
$PN"1"13;
"B"
$PN"2"51;
%"UNIVERSAL_POWER"
"1","(-4800,4450)","2","pure_quanta_power","I51";
;
HDL_POWER"P1V8_AUX"
CDS_LIB"pure_quanta_power";
"A"13;
%"Q_RES"
"2","(-4075,5150)","2","pure_quanta","I52";
;
LOCATION"R1265"
$SEC"1"
CDS_SEC"1"
VALUE"10K"
PACK_TYPE"0402LF"
TOLERANCE"5%"
MATERIAL"CHIP"
WATTAGE"1/16W"
CDS_LIB"pure_quanta"
PART_NUMBER"CS31002JB08";
"A"
$PN"1"44;
"B"
$PN"2"14;
%"UNIVERSAL_GND"
"1","(-4075,4950)","2","pure_quanta_power","I53";
;
CDS_LIB"pure_quanta_power"
HDL_POWER"GND";
"A"14;
%"Q_RES"
"2","(-4850,5725)","0","pure_quanta","I54";
;
LOCATION"R22"
$SEC"1"
CDS_SEC"1"
WATTAGE"1/16W"
MATERIAL"CHIP"
TOLERANCE"1%"
VALUE"100"
PACK_TYPE"0402LF"
CDS_LIB"pure_quanta"
PART_NUMBER"CS11002FB07";
"A"
$PN"1"15;
"B"
$PN"2"40;
%"UNIVERSAL_POWER"
"1","(-4850,5925)","2","pure_quanta_power","I55";
;
HDL_POWER"P1V8_AUX"
CDS_LIB"pure_quanta_power";
"A"15;
%"Q_RES"
"1","(-8900,1050)","0","pure_quanta","I6";
;
LOCATION"R1508"
$SEC"1"
CDS_SEC"1"
VALUE"100"
TOLERANCE"1%"
PACK_TYPE"0402LF"
MATERIAL"CHIP"
WATTAGE"1/16W"
CDS_LIB"pure_quanta"
PART_NUMBER"CS11002FB07";
"B"
$PN"2"33;
"A"
$PN"1"12;
%"UNIVERSAL_GND"
"1","(-2425,825)","2","pure_quanta_power","I60";
;
CDS_LIB"pure_quanta_power"
HDL_POWER"GND";
"A"16;
%"Q_RES"
"1","(-2425,1175)","1","pure_quanta","I61";
;
LOCATION"R6043"
$SEC"1"
CDS_SEC"1"
VALUE"100K"
MATERIAL"CHIP"
CDS_LIB"pure_quanta"
PACK_TYPE"0402LF"
WATTAGE"1/16W"
TOLERANCE"1%"
PART_NUMBER"CS41002FB09";
"B"
$PN"2"46;
"A"
$PN"1"16;
%"Q_RES"
"2","(-2425,1550)","2","pure_quanta","I62";
;
LOCATION"R6042"
$SEC"1"
CDS_SEC"1"
VALUE"10K"
PACK_TYPE"0402LF"
TOLERANCE"5%"
MATERIAL"CHIP"
WATTAGE"1/16W"
CDS_LIB"pure_quanta"
PART_NUMBER"CS31002JB08";
"A"
$PN"1"17;
"B"
$PN"2"47;
%"UNIVERSAL_POWER"
"1","(-2425,1750)","2","pure_quanta_power","I63";
;
HDL_POWER"P3V3_AUX"
CDS_LIB"pure_quanta_power";
"A"17;
%"UNIVERSAL_GND"
"1","(-1000,800)","2","pure_quanta_power","I66";
;
CDS_LIB"pure_quanta_power"
HDL_POWER"GND";
"A"18;
%"Q_RES"
"1","(-1000,1150)","1","pure_quanta","I69";
;
LOCATION"R6041"
$SEC"1"
CDS_SEC"1"
VALUE"100K"
MATERIAL"CHIP"
TOLERANCE"1%"
WATTAGE"1/16W"
PACK_TYPE"0402LF"
CDS_LIB"pure_quanta"
PART_NUMBER"CS41002FB09";
"B"
$PN"2"41;
"A"
$PN"1"18;
%"Q_RES"
"2","(-1000,1525)","2","pure_quanta","I70";
;
LOCATION"R6040"
$SEC"1"
CDS_SEC"1"
VALUE"10K"
CDS_LIB"pure_quanta"
WATTAGE"1/16W"
MATERIAL"CHIP"
TOLERANCE"5%"
PACK_TYPE"0402LF"
PART_NUMBER"CS31002JB08";
"A"
$PN"1"19;
"B"
$PN"2"45;
%"UNIVERSAL_POWER"
"1","(-1000,1725)","2","pure_quanta_power","I71";
;
HDL_POWER"P1V8_AUX"
CDS_LIB"pure_quanta_power";
"A"19;
%"Q_RES"
"2","(-1525,2600)","2","pure_quanta","I72";
;
LOCATION"R1358"
$SEC"1"
CDS_SEC"1"
VALUE"10K"
PACK_TYPE"0402LF"
TOLERANCE"5%"
WATTAGE"1/16W"
CDS_LIB"pure_quanta"
MATERIAL"EMPTY"
PART_NUMBER"CS31002JB08";
"A"
$PN"1"20;
"B"
$PN"2"28;
%"UNIVERSAL_POWER"
"1","(-1525,2800)","2","pure_quanta_power","I73";
;
HDL_POWER"P1V8_AUX"
CDS_LIB"pure_quanta_power";
"A"20;
%"Q_RES"
"2","(-1775,4100)","0","pure_quanta","I74";
;
LOCATION"R1357"
$SEC"1"
CDS_SEC"1"
MATERIAL"CHIP"
TOLERANCE"5%"
PACK_TYPE"0402LF"
WATTAGE"1/16W"
VALUE"2.2K"
CDS_LIB"pure_quanta"
PART_NUMBER"CS22202JB07";
"A"
$PN"1"21;
"B"
$PN"2"39;
%"UNIVERSAL_POWER"
"1","(-1775,4350)","0","pure_quanta_power","I76";
;
HDL_POWER"P3V3_AUX"
CDS_LIB"pure_quanta_power";
"A"21;
%"Q_RES"
"2","(-1775,5750)","0","pure_quanta","I77";
;
LOCATION"R1356"
$SEC"1"
CDS_SEC"1"
PACK_TYPE"0402LF"
VALUE"4.7K"
TOLERANCE"5%"
MATERIAL"CHIP"
WATTAGE"1/16W"
CDS_LIB"pure_quanta"
PART_NUMBER"CS24702JB10";
"A"
$PN"1"22;
"B"
$PN"2"38;
%"UNIVERSAL_POWER"
"1","(-1775,6000)","0","pure_quanta_power","I78";
;
HDL_POWER"P3V3_AUX"
CDS_LIB"pure_quanta_power";
"A"22;
%"UNIVERSAL_GND"
"1","(-8200,1300)","5","pure_quanta_power","I79";
;
CDS_LIB"pure_quanta_power"
HDL_POWER"GND";
"A"23;
%"UNIVERSAL_POWER"
"1","(-1100,2800)","2","pure_quanta_power","I80";
;
HDL_POWER"PVDD18_S5_P0"
CDS_LIB"pure_quanta_power";
"A"24;
%"Q_RES"
"2","(-1100,2600)","2","pure_quanta","I81";
;
LOCATION"R6106"
$SEC"1"
CDS_SEC"1"
VALUE"10K"
PACK_TYPE"0402LF"
TOLERANCE"5%"
MATERIAL"CHIP"
WATTAGE"1/16W"
CDS_LIB"pure_quanta"
PART_NUMBER"CS31002JB08";
"A"
$PN"1"24;
"B"
$PN"2"28;
%"UNIVERSAL_POWER"
"1","(-4600,2650)","2","pure_quanta_power","I82";
;
HDL_POWER"PVDD18_S5_P0"
CDS_LIB"pure_quanta_power";
"A"25;
%"Q_RES"
"2","(-4600,2450)","2","pure_quanta","I83";
;
LOCATION"R6107"
$SEC"1"
CDS_SEC"1"
VALUE"10K"
CDS_LIB"pure_quanta"
WATTAGE"1/16W"
MATERIAL"CHIP"
TOLERANCE"5%"
PACK_TYPE"0402LF"
PART_NUMBER"CS31002JB08";
"A"
$PN"1"25;
"B"
$PN"2"29;
%"Q_RES"
"2","(-4500,1550)","0","pure_quanta","I84";
;
LOCATION"R8018"
$SEC"1"
CDS_SEC"1"
VALUE"0"
MATERIAL"CHIP"
TOLERANCE"5%"
WATTAGE"1/16W"
PACK_TYPE"0402LF"
CDS_LIB"pure_quanta"
PART_NUMBER"CS00002JB13";
"A"
$PN"1"26;
"B"
$PN"2"62;
%"Q_RES"
"2","(-4750,1550)","2","pure_quanta","I85";
;
LOCATION"R8017"
SEC"1"
VALUE"0"
TOLERANCE"5%"
PACK_TYPE"0402LF"
MATERIAL"EMPTY"
WATTAGE"1/16W"
SEC_TYPE"0402LF"
CDS_LIB"pure_quanta"
PART_NUMBER"CS00002JB13";
"A"
$PN"1"8;
"B"
$PN"2"62;
%"UNIVERSAL_POWER"
"1","(-4500,1825)","2","pure_quanta_power","I86";
;
HDL_POWER"P1V8_AUX"
CDS_LIB"pure_quanta_power";
"A"26;
%"UNIVERSAL_POWER"
"1","(-5475,1225)","2","pure_quanta_power","I87";
;
HDL_POWER"P3V3_AUX"
CDS_LIB"pure_quanta_power";
"A"27;
%"Q_RES"
"2","(-5475,1000)","0","pure_quanta","I89";
;
LOCATION"R8019"
$SEC"1"
CDS_SEC"1"
VALUE"100"
TOLERANCE"1%"
PACK_TYPE"0402LF"
MATERIAL"EMPTY"
WATTAGE"1/16W"
CDS_LIB"pure_quanta"
PART_NUMBER"CS11002FB07";
"A"
$PN"1"27;
"B"
$PN"2"50;
%"SW20S_DHNF10FQTR"
"1","(-7625,1075)","0","pure_quanta","I90";
;
LOCATION"SW1"
SEC"1"
MATERIAL"MECH"
VALUE"SW20S_DHNF-10F-Q-T/R"
PART_TYPE"SMLF"
CDS_LMAN_SYM_OUTLINE"-100,275,100,-275"
NEEDS_NO_SIZE"TRUE"
CDS_LIB"pure_quanta"
SEC_TYPE""
PART_NUMBER"DHD00010F01";
"10"
$PN"10"37;
"9"
$PN"9"7;
"20"
$PN"20"36;
"19"
$PN"19"35;
"18"
$PN"18"59;
"17"
$PN"17"54;
"16"
$PN"16"34;
"15"
$PN"15"60;
"8"
$PN"8"53;
"7"
$PN"7"52;
"6"
$PN"6"33;
"5"
$PN"5"32;
"14"
$PN"14"31;
"13"
$PN"13"61;
"12"
$PN"12"55;
"11"
$PN"11"56;
"4"
$PN"4"58;
"3"
$PN"3"1;
"2"
$PN"2"57;
"1"
$PN"1"23;
END.
